# S9S_MB_2U (Grand Teton) — schematic netlist excerpt (pin names and nets, part order shuffled) for the footprints in the layout excerpt that follows; sources: Cadence DE-HDL packaged netlist, KiCad conversion of 03242023_DA0F0TMBIJ0_F0T_Motherboard_J_brd_V01_OCP.brd

D69  Q_LED  IC  pkg SMLF  page 256 : A = LED_RST_PLD_CPU1_DRAM_AB_N ; C = LED_RST_PLD_CPU1_DRAM_AB_N_D
R2790  Q_RES  0 5% EMPTY  pkg 0402LF  page 152 : A = USB2_HOST_BMC_B_DP ; B = USB2_HOST_BMC_B_BUF_DP

(kicad_pcb
	(version 20260206)
	(generator "pcbnew")
	(generator_version "10.0")
	(general
		(thickness 1.6)
		(legacy_teardrops no)
	)
	(paper "A4")
	(title_block
		(title "03242023_DA0F0TMBIJ0_F0T_Motherboard_J_brd_V01_OCP.brd")
		(comment 1 "Grand Teton / footprints 2360-2361 of 6105")
	)
	(layers
		(0 "F.Cu" signal "TOP")
		(4 "In1.Cu" signal "GND")
		(6 "In2.Cu" signal "IN1")
		(8 "In3.Cu" signal "GND1")
		(10 "In4.Cu" signal "IN2")
		(12 "In5.Cu" signal "GND2")
		(14 "In6.Cu" signal "IN3")
		(16 "In7.Cu" signal "GND3")
		(18 "In8.Cu" signal "VCC")
		(20 "In9.Cu" signal "VCC1")
		(22 "In10.Cu" signal "GND4")
		(24 "In11.Cu" signal "IN4")
		(26 "In12.Cu" signal "GND5")
		(28 "In13.Cu" signal "IN5")
		(30 "In14.Cu" signal "GND6")
		(32 "In15.Cu" signal "IN6")
		(34 "In16.Cu" signal "GND7")
		(2 "B.Cu" signal "BOTTOM")
		(9 "F.Adhes" user "F.Adhesive")
		(11 "B.Adhes" user "B.Adhesive")
		(13 "F.Paste" user "Package Geometry/Pastemask Top")
		(15 "B.Paste" user "Package Geometry/Pastemask Bottom")
		(5 "F.SilkS" user "Ref Des/Silkscreen Top")
		(7 "B.SilkS" user "Ref Des/Silkscreen Bottom")
		(1 "F.Mask" user "Board Geometry/Soldermask Top")
		(3 "B.Mask" user "Board Geometry/Soldermask Bottom")
		(17 "Dwgs.User" user "User.Drawings")
		(19 "Cmts.User" user "User.Comments")
		(21 "Eco1.User" user "User.Eco1")
		(23 "Eco2.User" user "User.Eco2")
		(25 "Edge.Cuts" user "Board Geometry/Outline")
		(27 "Margin" user)
		(31 "F.CrtYd" user "Package Geometry/Place Bound Top")
		(29 "B.CrtYd" user "Package Geometry/Place Bound Bottom")
		(35 "F.Fab" user "Ref Des/Assembly Top")
		(33 "B.Fab" user "Ref Des/Assembly Bottom")
	)
	(footprint ""
		(layer "F.Cu")
		(at 15.288006 -105.53573 90)
		(property "Reference" "R2790"
			(at 0 0 90)
			(layer "F.SilkS")
			(hide yes)
			(effects
				(font
					(size 1.27 1.27)
				)
			)
		)
		(property "Value" ""
			(at 0 0 90)
			(layer "F.Fab")
			(effects
				(font
					(size 1.27 1.27)
				)
			)
		)
		(duplicate_pad_numbers_are_jumpers no)
		(fp_line
			(start -0.02667 -0.4064)
			(end 0.7874 -0.4064)
			(stroke
				(width 0.1524)
				(type default)
			)
			(layer "F.SilkS")
		)
		(fp_line
			(start 0.7874 0.4064)
			(end 0.00127 0.4064)
			(stroke
				(width 0.1524)
				(type default)
			)
			(layer "F.SilkS")
		)
		(fp_line
			(start -0.7874 0.4064)
			(end -0.7874 -0.4064)
			(stroke
				(width 0.1524)
				(type default)
			)
			(layer "F.SilkS")
		)
		(fp_line
			(start -0.12065 -0.305054)
			(end -0.12065 -0.2794)
			(stroke
				(width 0.1)
				(type default)
			)
			(layer "F.Fab")
		)
		(fp_line
			(start -0.67945 -0.305054)
			(end -0.12065 -0.305054)
			(stroke
				(width 0.1)
				(type default)
			)
			(layer "F.Fab")
		)
		(fp_line
			(start 0.67945 -0.3048)
			(end 0.67945 0.3048)
			(stroke
				(width 0.1)
				(type default)
			)
			(layer "F.Fab")
		)
		(fp_line
			(start 0.12065 -0.3048)
			(end 0.67945 -0.3048)
			(stroke
				(width 0.1)
				(type default)
			)
			(layer "F.Fab")
		)
		(fp_line
			(start 0.12065 -0.2794)
			(end 0.12065 -0.3048)
			(stroke
				(width 0.1)
				(type default)
			)
			(layer "F.Fab")
		)
		(fp_line
			(start -0.12065 -0.2794)
			(end 0.12065 -0.2794)
			(stroke
				(width 0.1)
				(type default)
			)
			(layer "F.Fab")
		)
		(fp_line
			(start 0.120396 0.2794)
			(end -0.12065 0.2794)
			(stroke
				(width 0.1)
				(type default)
			)
			(layer "F.Fab")
		)
		(fp_line
			(start -0.12065 0.2794)
			(end -0.12065 0.3048)
			(stroke
				(width 0.1)
				(type default)
			)
			(layer "F.Fab")
		)
		(fp_line
			(start 0.67945 0.3048)
			(end 0.120396 0.3048)
			(stroke
				(width 0.1)
				(type default)
			)
			(layer "F.Fab")
		)
		(fp_line
			(start 0.120396 0.3048)
			(end 0.120396 0.2794)
			(stroke
				(width 0.1)
				(type default)
			)
			(layer "F.Fab")
		)
		(fp_line
			(start -0.12065 0.3048)
			(end -0.67945 0.3048)
			(stroke
				(width 0.1)
				(type default)
			)
			(layer "F.Fab")
		)
		(fp_line
			(start -0.67945 0.3048)
			(end -0.67945 -0.305054)
			(stroke
				(width 0.1)
				(type default)
			)
			(layer "F.Fab")
		)
		(pad "1" smd rect
			(at -0.40005 0 270)
			(size 0.4572 0.508)
			(layers "F.Cu" "F.Mask" "F.Paste")
			(net "USB2_HOST_BMC_B_DP")
		)
		(pad "2" smd rect
			(at 0.40005 0 270)
			(size 0.4572 0.508)
			(layers "F.Cu" "F.Mask" "F.Paste")
			(net "USB2_HOST_BMC_B_BUF_DP")
		)
	)
	(footprint ""
		(layer "F.Cu")
		(at 68.179696 -70.78599)
		(property "Reference" "D69"
			(at -36.052506 50.178462 90)
			(unlocked yes)
			(layer "F.SilkS")
			(effects
				(font
					(size 0.635 0.4064)
					(thickness 0.1524)
				)
				(justify left)
			)
		)
		(property "Value" ""
			(at 0 0 0)
			(layer "F.Fab")
			(effects
				(font
					(size 1.27 1.27)
				)
			)
		)
		(duplicate_pad_numbers_are_jumpers no)
		(fp_line
			(start -0.90678 0.4826)
			(end -0.90678 -0.4699)
			(stroke
				(width 0.1524)
				(type default)
			)
			(layer "F.SilkS")
		)
		(fp_line
			(start -0.89408 -0.4826)
			(end 0.90678 -0.4826)
			(stroke
				(width 0.1524)
				(type default)
			)
			(layer "F.SilkS")
		)
		(fp_line
			(start -0.79248 -0.4826)
			(end 1.03378 -0.4826)
			(stroke
				(width 0.1524)
				(type default)
			)
			(layer "F.SilkS")
		)
		(fp_line
			(start -0.64008 -0.4826)
			(end 1.16078 -0.4826)
			(stroke
				(width 0.1524)
				(type default)
			)
			(layer "F.SilkS")
		)
		(fp_line
			(start 0.90678 -0.4826)
			(end 0.90678 0.4826)
			(stroke
				(width 0.1524)
				(type default)
			)
			(layer "F.SilkS")
		)
		(fp_line
			(start 0.90678 0.4826)
			(end -0.90678 0.4826)
			(stroke
				(width 0.1524)
				(type default)
			)
			(layer "F.SilkS")
		)
		(fp_line
			(start 1.03378 -0.4826)
			(end 1.03378 0.4826)
			(stroke
				(width 0.1524)
				(type default)
			)
			(layer "F.SilkS")
		)
		(fp_line
			(start 1.03378 0.4826)
			(end -0.79248 0.4826)
			(stroke
				(width 0.1524)
				(type default)
			)
			(layer "F.SilkS")
		)
		(fp_line
			(start 1.16078 -0.4826)
			(end 1.16078 0.4826)
			(stroke
				(width 0.1524)
				(type default)
			)
			(layer "F.SilkS")
		)
		(fp_line
			(start 1.16078 0.4826)
			(end -0.64008 0.4826)
			(stroke
				(width 0.1524)
				(type default)
			)
			(layer "F.SilkS")
		)
		(fp_line
			(start -0.499872 -0.249936)
			(end 0.499872 -0.249936)
			(stroke
				(width 0.1)
				(type default)
			)
			(layer "F.Fab")
		)
		(fp_line
			(start -0.499872 0.249936)
			(end -0.499872 -0.249936)
			(stroke
				(width 0.1)
				(type default)
			)
			(layer "F.Fab")
		)
		(fp_line
			(start 0.499872 -0.249936)
			(end 0.499872 0.249936)
			(stroke
				(width 0.1)
				(type default)
			)
			(layer "F.Fab")
		)
		(fp_line
			(start 0.499872 0.249936)
			(end -0.499872 0.249936)
			(stroke
				(width 0.1)
				(type default)
			)
			(layer "F.Fab")
		)
		(pad "A" smd rect
			(at -0.47498 0)
			(size 0.6096 0.7112)
			(layers "F.Cu" "F.Mask" "F.Paste")
			(net "LED_RST_PLD_CPU1_DRAM_AB_N")
		)
		(pad "C" smd rect
			(at 0.47498 0)
			(size 0.6096 0.7112)
			(layers "F.Cu" "F.Mask" "F.Paste")
			(net "LED_RST_PLD_CPU1_DRAM_AB_N_D")
		)
	)
)
